G04 ================== begin FILE IDENTIFICATION RECORD ==================*
G04 Layout Name:  15968-1a.brd*
G04 Film Name:    L5GND*
G04 File Format:  Gerber RS274X*
G04 File Origin:  Cadence Allegro 16.5-S058*
G04 Origin Date:  Fri Oct 14 10:23:43 2016*
G04 *
G04 Layer:  VIA CLASS/L5GND*
G04 Layer:  PIN/L5GND*
G04 Layer:  ETCH/L5GND*
G04 Layer:  DRAWING FORMAT/LAYER_PCB_STORY*
G04 Layer:  DRAWING FORMAT/LAYER_L5GND*
G04 *
G04 Offset:    (0.00 0.00)*
G04 Mirror:    No*
G04 Mode:      Negative*
G04 Rotation:  0*
G04 FullContactRelief:  No*
G04 UndefLineWidth:     6.00*
G04 ================== end FILE IDENTIFICATION RECORD ====================*
%FSLAX35Y35*MOIN*%
%IR0*IPPOS*OFA0.00000B0.00000*MIA0B0*SFA1.00000B1.00000*%
%AMMACRO12*
4,1,16,.0821,-.02,
.07738,-.033953,
.070308,-.046874,
.061101,-.058371,
.050036,-.068094,
.037452,-.075748,
.023729,-.081101,
.02,-.0821,
.02,-.08724,
.034845,-.082442,
.048632,-.075138,
.060941,-.065552,
.071398,-.053974,
.079685,-.040756,
.085552,-.026299,
.08724,-.02,
.0821,-.02,
0.0*
4,1,16,-.02,-.0821,
-.033953,-.07738,
-.046874,-.070308,
-.058371,-.061101,
-.068094,-.050036,
-.075748,-.037452,
-.081101,-.023729,
-.0821,-.02,
-.08724,-.02,
-.082442,-.034845,
-.075138,-.048632,
-.065552,-.060941,
-.053974,-.071398,
-.040756,-.079685,
-.026299,-.085552,
-.02,-.08724,
-.02,-.0821,
0.0*
4,1,16,-.0821,.02,
-.07738,.033953,
-.070308,.046874,
-.061101,.058371,
-.050036,.068094,
-.037452,.075748,
-.023729,.081101,
-.02,.0821,
-.02,.08724,
-.034845,.082442,
-.048632,.075138,
-.060941,.065552,
-.071398,.053974,
-.079685,.040756,
-.085552,.026299,
-.08724,.02,
-.0821,.02,
0.0*
4,1,16,.02,.0821,
.033953,.07738,
.046874,.070308,
.058371,.061101,
.068094,.050036,
.075748,.037452,
.081101,.023729,
.0821,.02,
.08724,.02,
.082442,.034845,
.075138,.048632,
.065552,.060941,
.053974,.071398,
.040756,.079685,
.026299,.085552,
.02,.08724,
.02,.0821,
0.0*
%
%ADD12MACRO12*%
%ADD14C,.03*%
%ADD11C,.032*%
%ADD17C,.056*%
%AMMACRO15*
4,1,15,.00398,.00044,
.003999,.000208,
.004004,-.000025,
.003996,-.000258,
.00398,-.00044,
.00483,-.00129,
.004897,-.001007,
.004947,-.000721,
.004981,-.000432,
.004997,-.000141,
.004997,.000149,
.00498,.00044,
.004946,.000729,
.004895,.001015,
.00483,.00129,
.00398,.00044,
90.*
4,1,15,.00044,-.00398,
.000208,-.003999,
-.000025,-.004004,
-.000258,-.003996,
-.00044,-.00398,
-.00129,-.00483,
-.001007,-.004897,
-.000721,-.004947,
-.000432,-.004981,
-.000141,-.004997,
.000149,-.004997,
.00044,-.00498,
.000729,-.004946,
.001015,-.004895,
.00129,-.00483,
.00044,-.00398,
90.*
4,1,15,-.00398,-.00044,
-.003999,-.000208,
-.004004,.000025,
-.003996,.000258,
-.00398,.00044,
-.00483,.00129,
-.004897,.001007,
-.004947,.000721,
-.004981,.000432,
-.004997,.000141,
-.004997,-.000149,
-.00498,-.00044,
-.004946,-.000729,
-.004895,-.001015,
-.00483,-.00129,
-.00398,-.00044,
90.*
4,1,15,-.00044,.00398,
-.000208,.003999,
.000025,.004004,
.000258,.003996,
.00044,.00398,
.00129,.00483,
.001007,.004897,
.000721,.004947,
.000432,.004981,
.000141,.004997,
-.000149,.004997,
-.00044,.00498,
-.000729,.004946,
-.001015,.004895,
-.00129,.00483,
-.00044,.00398,
90.*
%
%ADD15MACRO15*%
%AMMACRO13*
4,1,15,.00398,.00044,
.003999,.000208,
.004004,-.000025,
.003996,-.000258,
.00398,-.00044,
.00483,-.00129,
.004897,-.001007,
.004947,-.000721,
.004981,-.000432,
.004997,-.000141,
.004997,.000149,
.00498,.00044,
.004946,.000729,
.004895,.001015,
.00483,.00129,
.00398,.00044,
0.0*
4,1,15,.00044,-.00398,
.000208,-.003999,
-.000025,-.004004,
-.000258,-.003996,
-.00044,-.00398,
-.00129,-.00483,
-.001007,-.004897,
-.000721,-.004947,
-.000432,-.004981,
-.000141,-.004997,
.000149,-.004997,
.00044,-.00498,
.000729,-.004946,
.001015,-.004895,
.00129,-.00483,
.00044,-.00398,
0.0*
4,1,15,-.00398,-.00044,
-.003999,-.000208,
-.004004,.000025,
-.003996,.000258,
-.00398,.00044,
-.00483,.00129,
-.004897,.001007,
-.004947,.000721,
-.004981,.000432,
-.004997,.000141,
-.004997,-.000149,
-.00498,-.00044,
-.004946,-.000729,
-.004895,-.001015,
-.00483,-.00129,
-.00398,-.00044,
0.0*
4,1,15,-.00044,.00398,
-.000208,.003999,
.000025,.004004,
.000258,.003996,
.00044,.00398,
.00129,.00483,
.001007,.004897,
.000721,.004947,
.000432,.004981,
.000141,.004997,
-.000149,.004997,
-.00044,.00498,
-.000729,.004946,
-.001015,.004895,
-.00129,.00483,
-.00044,.00398,
0.0*
%
%ADD13MACRO13*%
%ADD20C,.111*%
%ADD16C,.121*%
%ADD10C,.114*%
%AMMACRO19*
4,1,15,.00398,.00044,
.003999,.000208,
.004004,-.000025,
.003996,-.000258,
.00398,-.00044,
.00483,-.00129,
.004897,-.001007,
.004947,-.000721,
.004981,-.000432,
.004997,-.000141,
.004997,.000149,
.00498,.00044,
.004946,.000729,
.004895,.001015,
.00483,.00129,
.00398,.00044,
270.*
4,1,15,.00044,-.00398,
.000208,-.003999,
-.000025,-.004004,
-.000258,-.003996,
-.00044,-.00398,
-.00129,-.00483,
-.001007,-.004897,
-.000721,-.004947,
-.000432,-.004981,
-.000141,-.004997,
.000149,-.004997,
.00044,-.00498,
.000729,-.004946,
.001015,-.004895,
.00129,-.00483,
.00044,-.00398,
270.*
4,1,15,-.00398,-.00044,
-.003999,-.000208,
-.004004,.000025,
-.003996,.000258,
-.00398,.00044,
-.00483,.00129,
-.004897,.001007,
-.004947,.000721,
-.004981,.000432,
-.004997,.000141,
-.004997,-.000149,
-.00498,-.00044,
-.004946,-.000729,
-.004895,-.001015,
-.00483,-.00129,
-.00398,-.00044,
270.*
4,1,15,-.00044,.00398,
-.000208,.003999,
.000025,.004004,
.000258,.003996,
.00044,.00398,
.00129,.00483,
.001007,.004897,
.000721,.004947,
.000432,.004981,
.000141,.004997,
-.000149,.004997,
-.00044,.00498,
-.000729,.004946,
-.001015,.004895,
-.00129,.00483,
-.00044,.00398,
270.*
%
%ADD19MACRO19*%
%AMMACRO18*
4,1,19,.02172,.00757,
.022123,.006294,
.022452,.004997,
.022705,.003683,
.02288,.002357,
.022979,.001023,
.022999,-.000315,
.022942,-.001652,
.022807,-.002983,
.022595,-.004304,
.022307,-.005611,
.021943,-.006898,
.02172,-.00757,
.02556,-.01142,
.027155,-.006808,
.027924,-.001989,
.027846,.00289,
.026921,.007681,
.02556,.01142,
.02172,.00757,
0.0*
4,1,19,.00757,-.02172,
.006294,-.022123,
.004997,-.022452,
.003683,-.022705,
.002357,-.02288,
.001023,-.022979,
-.000315,-.022999,
-.001652,-.022942,
-.002983,-.022807,
-.004304,-.022595,
-.005611,-.022307,
-.006898,-.021943,
-.00757,-.02172,
-.01142,-.02556,
-.006808,-.027155,
-.001989,-.027924,
.00289,-.027846,
.007681,-.026921,
.01142,-.02556,
.00757,-.02172,
0.0*
4,1,19,-.02172,-.00757,
-.022123,-.006294,
-.022452,-.004997,
-.022705,-.003683,
-.02288,-.002357,
-.022979,-.001023,
-.022999,.000315,
-.022942,.001652,
-.022807,.002983,
-.022595,.004304,
-.022307,.005611,
-.021943,.006898,
-.02172,.00757,
-.02556,.01142,
-.027155,.006808,
-.027924,.001989,
-.027846,-.00289,
-.026921,-.007681,
-.02556,-.01142,
-.02172,-.00757,
0.0*
4,1,19,-.00757,.02172,
-.006294,.022123,
-.004997,.022452,
-.003683,.022705,
-.002357,.02288,
-.001023,.022979,
.000315,.022999,
.001652,.022942,
.002983,.022807,
.004304,.022595,
.005611,.022307,
.006898,.021943,
.00757,.02172,
.01142,.02556,
.006808,.027155,
.001989,.027924,
-.00289,.027846,
-.007681,.026921,
-.01142,.02556,
-.00757,.02172,
0.0*
%
%ADD18MACRO18*%
%ADD21C,.02*%
%ADD22C,.006*%
%ADD23C,.11004*%
%ADD24C,.11704*%
%ADD25C,.12524*%
G75*
%LPD*%
G75*
G36*
G01X-6000Y-79346D02*
X621748D01*
Y247988D01*
X-6000D01*
Y-79346D01*
G37*
%LPC*%
G75*
G36*
G01X3004Y238051D02*
G02X3937Y238984I933J0D01*
G01X179423D01*
G02X179669Y238269I0J-400D01*
G03X178662Y235208I1789J-2285D01*
G01X178682Y235134D01*
X176534Y230840D01*
X176463Y230812D01*
G03X180314Y228886I1055J-2703D01*
G01X180294Y228960D01*
X182441Y233253D01*
X182513Y233281D01*
G03X183247Y238269I-1055J2703D01*
G02X183493Y238984I246J315D01*
G01X187298D01*
G02X187544Y238269I0J-400D01*
G03X188276Y233281I1789J-2285D01*
G01X188348Y233253D01*
X190493Y228960D01*
X190472Y228886D01*
G03X194325Y230812I2796J-777D01*
G01X194253Y230840D01*
X192108Y235132D01*
X192129Y235207D01*
G03X191122Y238269I-2796J777D01*
G02X191368Y238984I246J315D01*
G01X210918D01*
G02X211164Y238269I0J-400D01*
G03X210157Y235206I1789J-2285D01*
G01X210178Y235132D01*
X208033Y230840D01*
X207961Y230812D01*
G03X211814Y228886I1057J-2703D01*
G01X211793Y228960D01*
X213938Y233253D01*
X214010Y233281D01*
G03X214742Y238269I-1057J2703D01*
G02X214988Y238984I246J315D01*
G01X226668D01*
G02X226914Y238269I0J-400D01*
G03X225907Y235208I1789J-2285D01*
G01X225927Y235134D01*
X223779Y230840D01*
X223708Y230812D01*
G03X227559Y228886I1055J-2703D01*
G01X227539Y228960D01*
X229686Y233253D01*
X229758Y233281D01*
G03X230492Y238269I-1055J2703D01*
G02X230738Y238984I246J315D01*
G01X242413D01*
G02X242659Y238269I0J-400D01*
G03X241652Y235206I1789J-2285D01*
G01X241673Y235132D01*
X239528Y230840D01*
X239456Y230812D01*
G03X243309Y228886I1057J-2703D01*
G01X243288Y228960D01*
X245433Y233253D01*
X245505Y233281D01*
G03X246237Y238269I-1057J2703D01*
G02X246483Y238984I246J315D01*
G01X250288D01*
G02X250534Y238269I0J-400D01*
G03X251266Y233281I1789J-2285D01*
G01X251338Y233253D01*
X253483Y228960D01*
X253462Y228886D01*
G03X257315Y230812I2796J-777D01*
G01X257243Y230840D01*
X255098Y235132D01*
X255119Y235207D01*
G03X254112Y238269I-2796J777D01*
G02X254358Y238984I246J315D01*
G01X266038D01*
G02X266284Y238269I0J-400D01*
G03X265277Y235208I1789J-2285D01*
G01X265297Y235134D01*
X263149Y230840D01*
X263078Y230812D01*
G03X266929Y228886I1055J-2703D01*
G01X266909Y228960D01*
X269056Y233253D01*
X269128Y233281D01*
G03X269862Y238269I-1055J2703D01*
G02X270108Y238984I246J315D01*
G01X281783D01*
G02X282029Y238269I0J-400D01*
G03X281022Y235206I1789J-2285D01*
G01X281043Y235132D01*
X278898Y230840D01*
X278826Y230812D01*
G03X282679Y228886I1057J-2703D01*
G01X282658Y228960D01*
X284803Y233253D01*
X284875Y233281D01*
G03X285607Y238269I-1057J2703D01*
G02X285853Y238984I246J315D01*
G01X297533D01*
G02X297779Y238269I0J-400D01*
G03X296772Y235208I1789J-2285D01*
G01X296792Y235134D01*
X294644Y230840D01*
X294573Y230812D01*
G03X298424Y228886I1055J-2703D01*
G01X298404Y228960D01*
X300551Y233253D01*
X300623Y233281D01*
G03X301357Y238269I-1055J2703D01*
G02X301603Y238984I246J315D01*
G01X313278D01*
G02X313524Y238269I0J-400D01*
G03X312517Y235206I1789J-2285D01*
G01X312538Y235132D01*
X310393Y230840D01*
X310321Y230812D01*
G03X314174Y228886I1057J-2703D01*
G01X314153Y228960D01*
X316298Y233253D01*
X316370Y233281D01*
G03X317102Y238269I-1057J2703D01*
G02X317348Y238984I246J315D01*
G01X329028D01*
G02X329274Y238269I0J-400D01*
G03X329408Y233600I1789J-2285D01*
G01X329450Y233571D01*
X332100Y228268D01*
X332098Y228217D01*
G03X336652Y230493I2900J-108D01*
G01X336610Y230522D01*
X333961Y235824D01*
X333963Y235876D01*
G03X332852Y238269I-2900J108D01*
G02X333098Y238984I246J315D01*
G01X344778D01*
G02X345024Y238269I0J-400D01*
G03X345158Y233600I1789J-2285D01*
G01X345200Y233571D01*
X347850Y228268D01*
X347848Y228217D01*
G03X352402Y230493I2900J-108D01*
G01X352360Y230522D01*
X349711Y235824D01*
X349713Y235876D01*
G03X348602Y238269I-2900J108D01*
G02X348848Y238984I246J315D01*
G01X360523D01*
G02X360769Y238269I0J-400D01*
G03X360920Y233588I1789J-2285D01*
G01X360963Y233559D01*
X363601Y228286D01*
X363599Y228234D01*
G03X368136Y230504I2899J-125D01*
G01X368093Y230534D01*
X365455Y235807D01*
X365457Y235859D01*
G03X364347Y238269I-2899J125D01*
G02X364593Y238984I246J315D01*
G01X376273D01*
G02X376519Y238269I0J-400D01*
G03X376653Y233600I1789J-2285D01*
G01X376695Y233571D01*
X379345Y228268D01*
X379343Y228217D01*
G03X383897Y230493I2900J-108D01*
G01X383855Y230522D01*
X381206Y235824D01*
X381208Y235876D01*
G03X380097Y238269I-2900J108D01*
G02X380343Y238984I246J315D01*
G01X392018D01*
G02X392264Y238269I0J-400D01*
G03X392415Y233588I1789J-2285D01*
G01X392458Y233559D01*
X395096Y228286D01*
X395094Y228234D01*
G03X399631Y230504I2899J-125D01*
G01X399588Y230534D01*
X396950Y235807D01*
X396952Y235859D01*
G03X395842Y238269I-2899J125D01*
G02X396088Y238984I246J315D01*
G01X407768D01*
G02X408014Y238269I0J-400D01*
G03X408148Y233600I1789J-2285D01*
G01X408190Y233571D01*
X410840Y228268D01*
X410838Y228217D01*
G03X415392Y230493I2900J-108D01*
G01X415350Y230522D01*
X412701Y235824D01*
X412703Y235876D01*
G03X411592Y238269I-2900J108D01*
G02X411838Y238984I246J315D01*
G01X423518D01*
G02X423764Y238269I0J-400D01*
G03X423898Y233600I1789J-2285D01*
G01X423940Y233571D01*
X426590Y228268D01*
X426588Y228217D01*
G03X431142Y230493I2900J-108D01*
G01X431100Y230522D01*
X428451Y235824D01*
X428453Y235876D01*
G03X427342Y238269I-2900J108D01*
G02X427588Y238984I246J315D01*
G01X439263D01*
G02X439509Y238269I0J-400D01*
G03X439660Y233588I1789J-2285D01*
G01X439703Y233559D01*
X442341Y228286D01*
X442339Y228234D01*
G03X446876Y230504I2899J-125D01*
G01X446833Y230534D01*
X444195Y235807D01*
X444197Y235859D01*
G03X443087Y238269I-2899J125D01*
G02X443333Y238984I246J315D01*
G01X602308D01*
G02X602966Y238711I-1J-933D01*
G01X612471Y229206D01*
G02X612744Y228548I-660J-659D01*
G01Y163248D01*
G02X611811Y162315I-933J0D01*
G01X562598D01*
G03X562366Y162311I4J-6941D01*
G01X561354D01*
X561220Y162177D01*
X561162Y162165D01*
G03X555807Y156810I1436J-6791D01*
G01X555795Y156752D01*
X555660Y156617D01*
Y155575D01*
G03X555657Y155374I6938J-204D01*
G01Y9504D01*
G02X555384Y8845I-933J0D01*
G01X549817Y3277D01*
G02X549159Y3004I-660J660D01*
G01X544015D01*
G03X543783Y3000I4J-6941D01*
G01X542772D01*
X542638Y2866D01*
X542580Y2854D01*
G03X537225Y-2501I1436J-6791D01*
G01X537213Y-2559D01*
X537078Y-2694D01*
Y-3736D01*
G03X537075Y-3937I6938J-204D01*
G01Y-59195D01*
X443673D01*
Y-42636D01*
G03X443668Y-42448I-3791J-7D01*
G01Y-41395D01*
X443326Y-41054D01*
X443311Y-41023D01*
G03X441498Y-39208I-3430J-1614D01*
G01X441467Y-39193D01*
X441124Y-38850D01*
X440052D01*
G03X439883Y-38846I-174J-3787D01*
G01X406219D01*
G03X406050Y-38850I5J-3791D01*
G01X404976D01*
X404631Y-39195D01*
X404600Y-39210D01*
G03X402792Y-41019I1621J-3428D01*
G01X402777Y-41050D01*
X402432Y-41395D01*
Y-42491D01*
G03X402429Y-42637I3788J-151D01*
G01Y-58400D01*
X190248D01*
Y-52874D01*
G03X190243Y-52600I-7728J-4D01*
G01Y-51631D01*
X190128Y-51516D01*
X190117Y-51455D01*
G03X174923Y-51453I-7597J-1419D01*
G01X174912Y-51514D01*
X174794Y-51631D01*
Y-52662D01*
G03X174791Y-52874I7725J-215D01*
G01Y-58400D01*
X75957D01*
Y-3937D01*
G03X75952Y-3678I-6941J-4D01*
G01Y-2694D01*
X75819Y-2562D01*
X75807Y-2504D01*
G03X70449Y2854I-6791J-1433D01*
G01X70391Y2866D01*
X70258Y3000D01*
X69249D01*
G03X69017Y3004I-236J-6937D01*
G01X9503D01*
G02X8845Y3277I1J933D01*
G01X3277Y8845D01*
G02X3004Y9503I660J659D01*
G01Y238051D01*
G37*
%LPD*%
G75*
G36*
G01X530994Y-35788D02*
G02Y-40212I0J-2212D01*
G01X524993D01*
G02X524994Y-35788I1J2212D01*
G01X530994D01*
G37*
G36*
G01X453736Y102940D02*
G02Y107362I0J2211D01*
G01X457246D01*
G02X457245Y102940I-1J-2211D01*
G01X453736D01*
G37*
G36*
G01X459302Y52267D02*
G02X463724I2211J0D01*
G01Y48757D01*
G02X459302Y48758I-2211J1D01*
G01Y52267D01*
G37*
G36*
G01X449170Y91719D02*
G02X453592I2211J0D01*
G01Y88209D01*
G02X449170Y88210I-2211J1D01*
G01Y91719D01*
G37*
G36*
G01X350621Y-48676D02*
G02Y-44252I0J2212D01*
G01X354622D01*
G02X354621Y-48676I-1J-2212D01*
G01X350621D01*
G37*
G36*
G01X360821D02*
G02Y-44252I0J2212D01*
G01X364822D01*
G02X364821Y-48676I-1J-2212D01*
G01X360821D01*
G37*
G36*
G01X381221D02*
G02Y-44252I0J2212D01*
G01X385222D01*
G02X385221Y-48676I-1J-2212D01*
G01X381221D01*
G37*
G36*
G01X371021D02*
G02Y-44252I0J2212D01*
G01X375022D01*
G02X375021Y-48676I-1J-2212D01*
G01X371021D01*
G37*
G36*
G01X391421D02*
G02Y-44252I0J2212D01*
G01X395422D01*
G02X395421Y-48676I-1J-2212D01*
G01X391421D01*
G37*
G36*
G01X396642Y-38690D02*
G02Y-34268I0J2211D01*
G01X400643D01*
G02X400642Y-38690I-1J-2211D01*
G01X396642D01*
G37*
G36*
G01X386442D02*
G02Y-34268I0J2211D01*
G01X390443D01*
G02X390442Y-38690I-1J-2211D01*
G01X386442D01*
G37*
G36*
G01X376242D02*
G02Y-34268I0J2211D01*
G01X380243D01*
G02X380242Y-38690I-1J-2211D01*
G01X376242D01*
G37*
G36*
G01X366042D02*
G02Y-34268I0J2211D01*
G01X370043D01*
G02X370042Y-38690I-1J-2211D01*
G01X366042D01*
G37*
G36*
G01X355842D02*
G02Y-34268I0J2211D01*
G01X359843D01*
G02X359842Y-38690I-1J-2211D01*
G01X355842D01*
G37*
G36*
G01X320021Y-48676D02*
G02Y-44252I0J2212D01*
G01X324022D01*
G02X324021Y-48676I-1J-2212D01*
G01X320021D01*
G37*
G36*
G01X334221Y-44252D02*
G02Y-48676I0J-2212D01*
G01X330220D01*
G02X330221Y-44252I1J2212D01*
G01X334221D01*
G37*
G36*
G01X340421Y-48676D02*
G02Y-44252I0J2212D01*
G01X344422D01*
G02X344421Y-48676I-1J-2212D01*
G01X340421D01*
G37*
G36*
G01X345642Y-38690D02*
G02Y-34268I0J2211D01*
G01X349643D01*
G02X349642Y-38690I-1J-2211D01*
G01X345642D01*
G37*
G36*
G01X335442D02*
G02Y-34268I0J2211D01*
G01X339443D01*
G02X339442Y-38690I-1J-2211D01*
G01X335442D01*
G37*
G36*
G01X325242D02*
G02Y-34268I0J2211D01*
G01X329243D01*
G02X329242Y-38690I-1J-2211D01*
G01X325242D01*
G37*
G36*
G01X432368Y213097D02*
X432439Y213125D01*
X434587Y217419D01*
X434567Y217493D01*
G02X438418Y215566I2796J776D01*
G01X438346Y215538D01*
X436199Y211245D01*
X436219Y211171D01*
G02X432368Y213097I-2796J-777D01*
G37*
G36*
G01X416621D02*
X416693Y213125D01*
X418838Y217417D01*
X418817Y217491D01*
G02X422670Y215566I2796J778D01*
G01X422598Y215538D01*
X420453Y211245D01*
X420474Y211171D01*
G02X416621Y213097I-2796J-777D01*
G37*
G36*
G01X400873D02*
X400944Y213125D01*
X403092Y217419D01*
X403072Y217493D01*
G02X406923Y215566I2796J776D01*
G01X406851Y215538D01*
X404704Y211245D01*
X404724Y211171D01*
G02X400873Y213097I-2796J-777D01*
G37*
G36*
G01X385126D02*
X385198Y213125D01*
X387343Y217417D01*
X387322Y217491D01*
G02X391175Y215566I2796J778D01*
G01X391103Y215538D01*
X388958Y211245D01*
X388979Y211171D01*
G02X385126Y213097I-2796J-777D01*
G37*
G36*
G01X369376D02*
X369448Y213125D01*
X371593Y217417D01*
X371572Y217491D01*
G02X375425Y215566I2796J778D01*
G01X375353Y215538D01*
X373208Y211245D01*
X373229Y211171D01*
G02X369376Y213097I-2796J-777D01*
G37*
G36*
G01X353628D02*
X353699Y213125D01*
X355847Y217419D01*
X355827Y217493D01*
G02X359678Y215566I2796J776D01*
G01X359606Y215538D01*
X357459Y211245D01*
X357479Y211171D01*
G02X353628Y213097I-2796J-777D01*
G37*
G36*
G01X337881D02*
X337953Y213125D01*
X340098Y217417D01*
X340077Y217491D01*
G02X343930Y215566I2796J778D01*
G01X343858Y215538D01*
X341713Y211245D01*
X341734Y211171D01*
G02X337881Y213097I-2796J-777D01*
G37*
G36*
G01X322133D02*
X322204Y213125D01*
X324352Y217419D01*
X324332Y217493D01*
G02X328183Y215566I2796J776D01*
G01X328111Y215538D01*
X325964Y211245D01*
X325984Y211171D01*
G02X322133Y213097I-2796J-777D01*
G37*
G36*
G01X304647Y211171D02*
X304667Y211245D01*
X302520Y215538D01*
X302448Y215566D01*
G02X306299Y217493I1055J2703D01*
G01X306279Y217418D01*
X308427Y213125D01*
X308499Y213097D01*
G02X304647Y211171I-1056J-2703D01*
G37*
G36*
G01X288897D02*
X288918Y211245D01*
X286773Y215538D01*
X286701Y215566D01*
G02X290554Y217492I1057J2703D01*
G01X290533Y217417D01*
X292678Y213125D01*
X292750Y213097D01*
G02X288897Y211171I-1057J-2703D01*
G37*
G36*
G01X273147D02*
X273168Y211245D01*
X271023Y215538D01*
X270951Y215566D01*
G02X274804Y217492I1057J2703D01*
G01X274783Y217417D01*
X276928Y213125D01*
X277000Y213097D01*
G02X273147Y211171I-1057J-2703D01*
G37*
G36*
G01X257402D02*
X257422Y211245D01*
X255275Y215538D01*
X255203Y215566D01*
G02X259054Y217493I1055J2703D01*
G01X259034Y217418D01*
X261182Y213125D01*
X261254Y213097D01*
G02X257402Y211171I-1056J-2703D01*
G37*
G36*
G01X233777D02*
X233798Y211245D01*
X231653Y215538D01*
X231581Y215566D01*
G02X235434Y217492I1057J2703D01*
G01X235413Y217417D01*
X237558Y213125D01*
X237630Y213097D01*
G02X233777Y211171I-1057J-2703D01*
G37*
G36*
G01X218032D02*
X218052Y211245D01*
X215905Y215538D01*
X215833Y215566D01*
G02X219684Y217493I1055J2703D01*
G01X219664Y217418D01*
X221812Y213125D01*
X221884Y213097D01*
G02X218032Y211171I-1056J-2703D01*
G37*
G36*
G01X203939Y217492D02*
X203918Y217417D01*
X206063Y213125D01*
X206135Y213097D01*
G02X202282Y211171I-1057J-2703D01*
G01X202303Y211245D01*
X200158Y215538D01*
X200086Y215566D01*
G02X203939Y217492I1057J2703D01*
G37*
G36*
G01X186450Y215566D02*
X186378Y215538D01*
X184233Y211245D01*
X184254Y211171D01*
G02X180401Y213097I-2796J-777D01*
G01X180473Y213125D01*
X182618Y217417D01*
X182597Y217491D01*
G02X186450Y215566I2796J778D01*
G37*
G36*
G01X442442Y148886D02*
X442462Y148960D01*
X440315Y153253D01*
X440243Y153281D01*
G02X444094Y155208I1055J2703D01*
G01X444074Y155133D01*
X446222Y150840D01*
X446294Y150812D01*
G02X442442Y148886I-1056J-2703D01*
G37*
G36*
G01X426692D02*
X426713Y148960D01*
X424568Y153253D01*
X424496Y153281D01*
G02X428349Y155207I1057J2703D01*
G01X428328Y155132D01*
X430473Y150840D01*
X430545Y150812D01*
G02X426692Y148886I-1057J-2703D01*
G37*
G36*
G01X410942D02*
X410963Y148960D01*
X408818Y153253D01*
X408746Y153281D01*
G02X412599Y155207I1057J2703D01*
G01X412578Y155132D01*
X414723Y150840D01*
X414795Y150812D01*
G02X410942Y148886I-1057J-2703D01*
G37*
G36*
G01X395197D02*
X395217Y148960D01*
X393070Y153253D01*
X392998Y153281D01*
G02X396849Y155208I1055J2703D01*
G01X396829Y155133D01*
X398977Y150840D01*
X399049Y150812D01*
G02X395197Y148886I-1056J-2703D01*
G37*
G36*
G01X379447D02*
X379468Y148960D01*
X377323Y153253D01*
X377251Y153281D01*
G02X381104Y155207I1057J2703D01*
G01X381083Y155132D01*
X383228Y150840D01*
X383300Y150812D01*
G02X379447Y148886I-1057J-2703D01*
G37*
G36*
G01X363702D02*
X363722Y148960D01*
X361575Y153253D01*
X361503Y153281D01*
G02X365354Y155208I1055J2703D01*
G01X365334Y155133D01*
X367482Y150840D01*
X367554Y150812D01*
G02X363702Y148886I-1056J-2703D01*
G37*
G36*
G01X347952D02*
X347973Y148960D01*
X345828Y153253D01*
X345756Y153281D01*
G02X349609Y155207I1057J2703D01*
G01X349588Y155132D01*
X351733Y150840D01*
X351805Y150812D01*
G02X347952Y148886I-1057J-2703D01*
G37*
G36*
G01X333859Y155207D02*
X333838Y155132D01*
X335983Y150840D01*
X336055Y150812D01*
G02X332202Y148886I-1057J-2703D01*
G01X332223Y148960D01*
X330078Y153253D01*
X330006Y153281D01*
G02X333859Y155207I1057J2703D01*
G37*
G36*
G01X310321Y150812D02*
X310393Y150840D01*
X312538Y155132D01*
X312517Y155206D01*
G02X316370Y153281I2796J778D01*
G01X316298Y153253D01*
X314153Y148960D01*
X314174Y148886D01*
G02X310321Y150812I-2796J-777D01*
G37*
G36*
G01X294573D02*
X294644Y150840D01*
X296792Y155134D01*
X296772Y155208D01*
G02X300623Y153281I2796J776D01*
G01X300551Y153253D01*
X298404Y148960D01*
X298424Y148886D01*
G02X294573Y150812I-2796J-777D01*
G37*
G36*
G01X278826D02*
X278898Y150840D01*
X281043Y155132D01*
X281022Y155206D01*
G02X284875Y153281I2796J778D01*
G01X284803Y153253D01*
X282658Y148960D01*
X282679Y148886D01*
G02X278826Y150812I-2796J-777D01*
G37*
G36*
G01X263078D02*
X263149Y150840D01*
X265297Y155134D01*
X265277Y155208D01*
G02X269128Y153281I2796J776D01*
G01X269056Y153253D01*
X266909Y148960D01*
X266929Y148886D01*
G02X263078Y150812I-2796J-777D01*
G37*
G36*
G01X255119Y155207D02*
X255098Y155132D01*
X257243Y150840D01*
X257315Y150812D01*
G02X253462Y148886I-1057J-2703D01*
G01X253483Y148960D01*
X251338Y153253D01*
X251266Y153281D01*
G02X255119Y155207I1057J2703D01*
G37*
G36*
G01X239456Y150812D02*
X239528Y150840D01*
X241673Y155132D01*
X241652Y155206D01*
G02X245505Y153281I2796J778D01*
G01X245433Y153253D01*
X243288Y148960D01*
X243309Y148886D01*
G02X239456Y150812I-2796J-777D01*
G37*
G36*
G01X223708D02*
X223779Y150840D01*
X225927Y155134D01*
X225907Y155208D01*
G02X229758Y153281I2796J776D01*
G01X229686Y153253D01*
X227539Y148960D01*
X227559Y148886D01*
G02X223708Y150812I-2796J-777D01*
G37*
G36*
G01X207961D02*
X208033Y150840D01*
X210178Y155132D01*
X210157Y155206D01*
G02X214010Y153281I2796J778D01*
G01X213938Y153253D01*
X211793Y148960D01*
X211814Y148886D01*
G02X207961Y150812I-2796J-777D01*
G37*
G36*
G01X190472Y148886D02*
X190493Y148960D01*
X188348Y153253D01*
X188276Y153281D01*
G02X192129Y155207I1057J2703D01*
G01X192108Y155132D01*
X194253Y150840D01*
X194325Y150812D01*
G02X190472Y148886I-1057J-2703D01*
G37*
G36*
G01X182513Y153281D02*
X182441Y153253D01*
X180294Y148960D01*
X180314Y148886D01*
G02X176463Y150812I-2796J-777D01*
G01X176534Y150840D01*
X178682Y155134D01*
X178662Y155208D01*
G02X182513Y153281I2796J776D01*
G37*
G36*
G01X432368Y133097D02*
X432439Y133125D01*
X434587Y137419D01*
X434567Y137493D01*
G02X438418Y135566I2796J776D01*
G01X438346Y135538D01*
X436199Y131245D01*
X436219Y131171D01*
G02X432368Y133097I-2796J-777D01*
G37*
G36*
G01X416621D02*
X416693Y133125D01*
X418838Y137417D01*
X418817Y137491D01*
G02X422670Y135566I2796J778D01*
G01X422598Y135538D01*
X420453Y131245D01*
X420474Y131171D01*
G02X416621Y133097I-2796J-777D01*
G37*
G36*
G01X400873D02*
X400944Y133125D01*
X403092Y137419D01*
X403072Y137493D01*
G02X406923Y135566I2796J776D01*
G01X406851Y135538D01*
X404704Y131245D01*
X404724Y131171D01*
G02X400873Y133097I-2796J-777D01*
G37*
G36*
G01X385126D02*
X385198Y133125D01*
X387343Y137417D01*
X387322Y137491D01*
G02X391175Y135566I2796J778D01*
G01X391103Y135538D01*
X388958Y131245D01*
X388979Y131171D01*
G02X385126Y133097I-2796J-777D01*
G37*
G36*
G01X369376D02*
X369448Y133125D01*
X371593Y137417D01*
X371572Y137491D01*
G02X375425Y135566I2796J778D01*
G01X375353Y135538D01*
X373208Y131245D01*
X373229Y131171D01*
G02X369376Y133097I-2796J-777D01*
G37*
G36*
G01X353628D02*
X353699Y133125D01*
X355847Y137419D01*
X355827Y137493D01*
G02X359678Y135566I2796J776D01*
G01X359606Y135538D01*
X357459Y131245D01*
X357479Y131171D01*
G02X353628Y133097I-2796J-777D01*
G37*
G36*
G01X337881D02*
X337953Y133125D01*
X340098Y137417D01*
X340077Y137491D01*
G02X343930Y135566I2796J778D01*
G01X343858Y135538D01*
X341713Y131245D01*
X341734Y131171D01*
G02X337881Y133097I-2796J-777D01*
G37*
G36*
G01X322133D02*
X322204Y133125D01*
X324352Y137419D01*
X324332Y137493D01*
G02X328183Y135566I2796J776D01*
G01X328111Y135538D01*
X325964Y131245D01*
X325984Y131171D01*
G02X322133Y133097I-2796J-777D01*
G37*
G36*
G01X304647Y131171D02*
X304667Y131245D01*
X302520Y135538D01*
X302448Y135566D01*
G02X306299Y137493I1055J2703D01*
G01X306279Y137418D01*
X308427Y133125D01*
X308499Y133097D01*
G02X304647Y131171I-1056J-2703D01*
G37*
G36*
G01X288897D02*
X288918Y131245D01*
X286773Y135538D01*
X286701Y135566D01*
G02X290554Y137492I1057J2703D01*
G01X290533Y137417D01*
X292678Y133125D01*
X292750Y133097D01*
G02X288897Y131171I-1057J-2703D01*
G37*
G36*
G01X273147D02*
X273168Y131245D01*
X271023Y135538D01*
X270951Y135566D01*
G02X274804Y137492I1057J2703D01*
G01X274783Y137417D01*
X276928Y133125D01*
X277000Y133097D01*
G02X273147Y131171I-1057J-2703D01*
G37*
G36*
G01X257402D02*
X257422Y131245D01*
X255275Y135538D01*
X255203Y135566D01*
G02X259054Y137493I1055J2703D01*
G01X259034Y137418D01*
X261182Y133125D01*
X261254Y133097D01*
G02X257402Y131171I-1056J-2703D01*
G37*
G36*
G01X233777D02*
X233798Y131245D01*
X231653Y135538D01*
X231581Y135566D01*
G02X235434Y137492I1057J2703D01*
G01X235413Y137417D01*
X237558Y133125D01*
X237630Y133097D01*
G02X233777Y131171I-1057J-2703D01*
G37*
G36*
G01X218032D02*
X218052Y131245D01*
X215905Y135538D01*
X215833Y135566D01*
G02X219684Y137493I1055J2703D01*
G01X219664Y137418D01*
X221812Y133125D01*
X221884Y133097D01*
G02X218032Y131171I-1056J-2703D01*
G37*
G36*
G01X203939Y137492D02*
X203918Y137417D01*
X206063Y133125D01*
X206135Y133097D01*
G02X202282Y131171I-1057J-2703D01*
G01X202303Y131245D01*
X200158Y135538D01*
X200086Y135566D01*
G02X203939Y137492I1057J2703D01*
G37*
G36*
G01X186450Y135566D02*
X186378Y135538D01*
X184233Y131245D01*
X184254Y131171D01*
G02X180401Y133097I-2796J-777D01*
G01X180473Y133125D01*
X182618Y137417D01*
X182597Y137491D01*
G02X186450Y135566I2796J778D01*
G37*
G54D23*
X14794Y226306D03*
X542107Y17432D03*
X585785Y228866D03*
G54D24*
X168268Y143189D03*
Y223189D03*
X456258Y143189D03*
Y223189D03*
G54D25*
X561024Y190256D03*
Y206792D03*
G54D12*
X15748Y128150D03*
X542913D03*
G54D14*
X107400Y11300D03*
X98200Y10000D03*
X94042Y9842D03*
X87900Y94500D03*
X87250Y100650D03*
X98300Y67500D03*
X104500Y56200D03*
X88000Y65200D03*
X83200Y60000D03*
X48800Y87100D03*
X68800Y139000D03*
X59400Y151000D03*
X56400Y164250D03*
X67750Y160700D03*
X66100Y151000D03*
X98900Y172350D03*
X92400Y163100D03*
X80000Y158900D03*
X80400Y167200D03*
X102202Y131798D03*
X101500Y139900D03*
X100000Y175700D03*
X105500Y109500D03*
X105400Y153600D03*
X106500Y149000D03*
X105218Y137218D03*
X71500Y168500D03*
X56500Y202900D03*
X100500Y209300D03*
X75591Y202676D03*
X79843D03*
X83500Y189000D03*
X96000Y192000D03*
X72200Y202400D03*
X67500Y213500D03*
X64000D03*
X160400Y4900D03*
X111018Y11382D03*
X148300Y16700D03*
X147878Y13326D03*
X147900Y73800D03*
X153300Y22300D03*
X137400Y61900D03*
X125000Y93400D03*
X129400Y62200D03*
X169800Y39200D03*
X161400Y58700D03*
X154300Y56400D03*
X124100Y78900D03*
X137900Y49400D03*
X110781Y87200D03*
X111750Y98450D03*
X152900Y46500D03*
X114850Y95650D03*
X181700Y72700D03*
X161694Y55106D03*
X154300Y49600D03*
X111800Y113700D03*
X117600Y117700D03*
X116176Y156724D03*
X109500Y168752D03*
X180076Y179876D03*
X175600Y166800D03*
X121700Y117300D03*
X111924Y156724D03*
X109500Y164500D03*
X172000Y166800D03*
X124400Y103100D03*
X181400Y124500D03*
X172300Y192800D03*
X164200Y205100D03*
X180300Y187200D03*
X179900Y191300D03*
X180000Y198500D03*
Y183500D03*
X183683Y198517D03*
X173300Y204969D03*
X199400Y81400D03*
X236900Y85800D03*
X233700Y54400D03*
X246800Y112500D03*
X198300Y111700D03*
X188900Y173300D03*
X225100Y168100D03*
X199900Y161600D03*
X192200Y166700D03*
X195900Y162100D03*
X191600Y185600D03*
X209400Y200100D03*
X225600Y185900D03*
X230500Y191400D03*
X224100Y200100D03*
X256747Y199700D03*
X250100Y193000D03*
X267500Y182000D03*
X266000Y185100D03*
X254900Y188300D03*
X324021Y-46464D03*
X334221D03*
X344421D03*
X320021D03*
X330221D03*
X340421D03*
X329242Y-36479D03*
X339442D03*
X325242D03*
X335442D03*
X345642D03*
X329400Y50300D03*
X339100Y73300D03*
X324600Y36900D03*
X343524Y36971D03*
X346000Y34640D03*
X300800Y100100D03*
X337900Y46800D03*
X346150Y84800D03*
X313400Y119100D03*
X289600Y162100D03*
X308600Y171100D03*
X274400Y161700D03*
X327200Y178276D03*
Y174024D03*
X348200Y169900D03*
X294600Y201300D03*
X301500Y186300D03*
X332000Y192200D03*
X329400Y195900D03*
X334794Y195294D03*
X321600Y186300D03*
X323243Y183323D03*
X380500Y13200D03*
X380200Y3300D03*
X354621Y-46464D03*
X364821D03*
X375021D03*
X385221D03*
X395421D03*
X350621D03*
X360821D03*
X371021D03*
X381221D03*
X391421D03*
X349642Y-36479D03*
X359842D03*
X370042D03*
X380242D03*
X390442D03*
X400642D03*
X355842D03*
X366042D03*
X376242D03*
X386442D03*
X396642D03*
X383500Y69200D03*
X383600Y59618D03*
X383400Y46600D03*
X362400Y34500D03*
X404500Y36300D03*
X380200Y25800D03*
X349701Y64199D03*
X353100Y63900D03*
X359023Y47177D03*
X355370Y37411D03*
X355300Y81400D03*
X349700Y56000D03*
X349000Y28300D03*
X404500Y47769D03*
X409400Y69800D03*
X423500Y37800D03*
X412000Y29900D03*
X356700Y86600D03*
X353098Y55882D03*
X350300Y31800D03*
X352138Y50729D03*
X351500Y36100D03*
X355536Y50589D03*
X352700Y40000D03*
X355399Y47191D03*
X355300Y33900D03*
X391200Y35700D03*
X398805Y66200D03*
X408600Y27376D03*
X388006Y37706D03*
X395406Y66092D03*
X418650Y22850D03*
X408600Y23124D03*
X402500Y89124D03*
X375514Y85000D03*
X402500Y93376D03*
X372114Y85000D03*
X358700Y38100D03*
X362100D03*
X372400Y41100D03*
X433900Y11000D03*
X438900Y13400D03*
X428600Y16900D03*
X439000Y87700D03*
X451381Y88210D03*
Y91719D03*
X435287Y25646D03*
X441688Y74914D03*
X449400Y26433D03*
X454000Y40600D03*
X429850Y22950D03*
X461513Y48758D03*
Y52267D03*
X457245Y105151D03*
X453736D03*
X455700Y205800D03*
X524994Y-38000D03*
X530994D03*
X520500Y154500D03*
X525000Y158000D03*
X551376Y176271D03*
Y172019D03*
X517900Y103300D03*
X520970Y192569D03*
X528500Y200000D03*
G54D11*
X25700Y89200D03*
X27207Y85293D03*
X24400Y81900D03*
X22300Y85000D03*
X21800Y78600D03*
X21600Y74000D03*
X28200Y160400D03*
X84619Y-27663D03*
X89467Y-47981D03*
X84671Y-44973D03*
X79444Y-46817D03*
X90546Y-41425D03*
X90332Y-30191D03*
X85442Y-39927D03*
X79444Y-41282D03*
X90400Y-36500D03*
X85231Y-34026D03*
X79035Y-30696D03*
X79103Y-35748D03*
X107800Y4300D03*
X107000Y-49000D03*
X106800Y-53000D03*
X107100Y-36900D03*
X107500Y-33200D03*
X33200Y98700D03*
X30600Y88100D03*
X33700Y91400D03*
X29400Y92300D03*
X32800Y95000D03*
X102000Y40300D03*
X103000Y28300D03*
X105800Y40200D03*
X107000Y28300D03*
X96000Y80100D03*
X97800Y76800D03*
X93000Y73300D03*
X93800Y77000D03*
X89800Y76700D03*
X50700Y81900D03*
X58000Y81600D03*
X53000Y59800D03*
X49400Y60000D03*
X54300Y81700D03*
X71500Y39500D03*
X71700Y31500D03*
X69300Y36500D03*
X69400Y26700D03*
X86000Y36087D03*
X78600Y36200D03*
X74600Y36100D03*
X82300Y36200D03*
X32400Y160600D03*
X29200Y164000D03*
X33100Y164800D03*
X36000Y161800D03*
X31000Y156900D03*
X55600Y105100D03*
X54400Y110000D03*
X54600Y114900D03*
X59000Y107900D03*
X59700Y115200D03*
X44200Y212200D03*
X39200Y212100D03*
X44400Y217400D03*
X39300D03*
X111600Y4100D03*
X115500Y4000D03*
X119300Y3800D03*
X123000D03*
X127000Y3900D03*
X130800Y4000D03*
X111300Y-49100D03*
X111100Y-53100D03*
X111400Y-37000D03*
X111800Y-33300D03*
X131266Y85081D03*
X135025Y85092D03*
X138722Y85144D03*
X131666Y78581D03*
X135425Y78592D03*
X139122Y78644D03*
X109600Y40000D03*
X110800Y28100D03*
X138922Y94844D03*
X135225Y94792D03*
X131466Y94781D03*
X172300Y94300D03*
X169800Y91100D03*
X174900Y90900D03*
X152700Y33300D03*
X152279Y36876D03*
X153000Y40700D03*
X135100Y161900D03*
X155600Y166300D03*
X151700D03*
X134900Y165700D03*
X146165Y120044D03*
X140552Y117907D03*
X136626Y118116D03*
X158100Y116300D03*
X158000Y120900D03*
Y124800D03*
X142500Y203900D03*
X145300Y201100D03*
X148314Y203751D03*
X162100Y193800D03*
X165700Y195000D03*
X363700Y78200D03*
X421405Y90902D03*
X418437Y87727D03*
X423690Y87875D03*
X428500Y107700D03*
X424200Y103800D03*
X453500Y-9800D03*
X449900Y-9700D03*
X453400Y-13500D03*
X449800D03*
X453500Y-5700D03*
X449900D03*
X453600Y-2000D03*
X450000Y-1900D03*
X432100Y103800D03*
X495500Y219600D03*
Y210500D03*
X495400Y215300D03*
X500200Y219500D03*
X504800Y219600D03*
X504500Y210600D03*
X500200Y210400D03*
X504700Y215300D03*
X500100Y215200D03*
X540500Y219500D03*
X532200Y219300D03*
X527000Y219500D03*
X519900D03*
G54D17*
X122403Y148109D03*
X126338Y155984D03*
X130278Y148109D03*
X138148D03*
X142088Y155984D03*
X146023Y148109D03*
X149963Y155984D03*
X153898Y148109D03*
X157833Y155984D03*
X161773Y148109D03*
X177518D03*
X181458Y155984D03*
X189333D03*
X122403Y138269D03*
X126338Y130394D03*
X130278Y138269D03*
X138148D03*
X142088Y130394D03*
X149963D03*
X153898Y138269D03*
X157833Y130394D03*
X161773Y138269D03*
X173583Y130394D03*
X181458D03*
X185393Y138269D03*
X122403Y228109D03*
X126338Y235984D03*
X130278Y228109D03*
X138148D03*
X142088Y235984D03*
X146023Y228109D03*
X149963Y235984D03*
X153898Y228109D03*
X157833Y235984D03*
X161773Y228109D03*
X177518D03*
X181458Y235984D03*
X189333D03*
X122403Y218269D03*
X126338Y210394D03*
X130278Y218269D03*
X138148D03*
X142088Y210394D03*
X149963D03*
X153898Y218269D03*
X157833Y210394D03*
X161773Y218269D03*
X173583Y210394D03*
X181458D03*
X185393Y218269D03*
X193268Y148109D03*
X201143D03*
X209018D03*
X212953Y155984D03*
X224763Y148109D03*
X228703Y155984D03*
X240513Y148109D03*
X244448Y155984D03*
X252323D03*
X256258Y148109D03*
X264133D03*
X268073Y155984D03*
X193268Y138269D03*
X201143D03*
X205078Y130394D03*
X216888Y138269D03*
X220828Y130394D03*
X232638Y138269D03*
X236573Y130394D03*
X244448D03*
X248388Y138269D03*
X256258D03*
X260198Y130394D03*
X193268Y228109D03*
X201143D03*
X209018D03*
X212953Y235984D03*
X224763Y228109D03*
X228703Y235984D03*
X240513Y228109D03*
X244448Y235984D03*
X252323D03*
X256258Y228109D03*
X264133D03*
X268073Y235984D03*
X193268Y218269D03*
X201143D03*
X205078Y210394D03*
X216888Y218269D03*
X220828Y210394D03*
X232638Y218269D03*
X236573Y210394D03*
X244448D03*
X248388Y218269D03*
X256258D03*
X260198Y210394D03*
X279883Y148109D03*
X283818Y155984D03*
X295628Y148109D03*
X299568Y155984D03*
X311378Y148109D03*
X315313Y155984D03*
X323188D03*
X331063D03*
X334998Y148109D03*
X346813Y155984D03*
X272008Y138269D03*
X275943Y130394D03*
X287758Y138269D03*
X291693Y130394D03*
X303503Y138269D03*
X307443Y130394D03*
X315313D03*
X323188D03*
X327128Y138269D03*
X338938Y130394D03*
X342873Y138269D03*
X279883Y228109D03*
X283818Y235984D03*
X295628Y228109D03*
X299568Y235984D03*
X311378Y228109D03*
X315313Y235984D03*
X323188D03*
X331063D03*
X334998Y228109D03*
X346813Y235984D03*
X272008Y218269D03*
X275943Y210394D03*
X287758Y218269D03*
X291693Y210394D03*
X303503Y218269D03*
X307443Y210394D03*
X315313D03*
X323188D03*
X327128Y218269D03*
X338938Y210394D03*
X342873Y218269D03*
X350748Y148109D03*
X362558Y155984D03*
X366498Y148109D03*
X378308Y155984D03*
X382243Y148109D03*
X394053Y155984D03*
X397993Y148109D03*
X409803Y155984D03*
X413738Y148109D03*
X425553Y155984D03*
X429488Y148109D03*
X354683Y130394D03*
X358623Y138269D03*
X370433Y130394D03*
X374368Y138269D03*
X386183Y130394D03*
X390118Y138269D03*
X401928Y130394D03*
X405868Y138269D03*
X417678Y130394D03*
X421613Y138269D03*
X350748Y228109D03*
X362558Y235984D03*
X366498Y228109D03*
X378308Y235984D03*
X382243Y228109D03*
X394053Y235984D03*
X397993Y228109D03*
X409803Y235984D03*
X413738Y228109D03*
X425553Y235984D03*
X429488Y228109D03*
X354683Y210394D03*
X358623Y218269D03*
X370433Y210394D03*
X374368Y218269D03*
X386183Y210394D03*
X390118Y218269D03*
X401928Y210394D03*
X405868Y218269D03*
X417678Y210394D03*
X421613Y218269D03*
X441298Y155984D03*
X445238Y148109D03*
X433423Y130394D03*
X437363Y138269D03*
X445238D03*
X449173Y130394D03*
X441298Y235984D03*
X445238Y228109D03*
X433423Y210394D03*
X437363Y218269D03*
X445238D03*
X449173Y210394D03*
G54D15*
X83400Y55300D03*
X87300D03*
X75500Y55400D03*
X79099Y55280D03*
G54D13*
X6487Y175762D03*
Y165762D03*
X14947Y175971D03*
Y165971D03*
X22700Y190800D03*
X26300D03*
X26600Y201000D03*
X23000D03*
X6487Y235762D03*
X25453Y235870D03*
X15453D03*
X6487Y225762D03*
Y215762D03*
Y205762D03*
Y195762D03*
Y185762D03*
X14947Y195971D03*
Y185971D03*
X92940Y6625D03*
X99000Y13800D03*
X95906Y-53300D03*
X99200Y18100D03*
X76300Y79700D03*
X78900Y82400D03*
X78200Y76200D03*
X78300Y72600D03*
X78400Y68900D03*
X74700Y73100D03*
X73500Y76600D03*
X74900Y65800D03*
X74800Y69500D03*
X71000Y73500D03*
X67400Y76200D03*
X71100Y69800D03*
X67200Y72400D03*
Y68800D03*
X72400Y22300D03*
X90100Y23100D03*
X64200Y99200D03*
X78000Y99900D03*
X93900Y95300D03*
X104600Y95000D03*
X102400Y92600D03*
X106800Y92700D03*
X104600Y90500D03*
X45800Y54800D03*
X45200Y89400D03*
X30700Y56400D03*
X98300Y72000D03*
X39900Y72800D03*
X64600Y104500D03*
X78000Y105800D03*
X62000Y142900D03*
X56300Y180000D03*
X101500Y135908D03*
X62700Y150100D03*
X69000Y143300D03*
X79000Y142500D03*
X77000Y140300D03*
X81300Y140400D03*
X79200Y138100D03*
X104743Y174953D03*
X98900Y126800D03*
X85700Y129900D03*
X85900Y126300D03*
X81700Y129700D03*
X81800Y125900D03*
X100800Y189700D03*
X100700Y182900D03*
X98400Y233100D03*
X59600Y214000D03*
X100700Y186300D03*
X35453Y235870D03*
X45453D03*
X55453D03*
X65453D03*
X75453D03*
X84400Y232900D03*
X89600D03*
X94900Y233000D03*
X161100Y13600D03*
X126800Y-53409D03*
X135182D03*
X144631D03*
X154080D03*
X163529D03*
X172977D03*
X116900Y-35400D03*
X121801Y16999D03*
X146600Y3400D03*
X159450Y8750D03*
X182000Y66700D03*
X174400Y32500D03*
X176300Y45200D03*
X159450Y97400D03*
X151150Y83500D03*
X124900Y88900D03*
X161800Y71100D03*
X117200Y65750D03*
X116900Y59450D03*
X134000Y63400D03*
X151550Y87500D03*
X132600Y39900D03*
X167100Y181200D03*
X156600Y109800D03*
X152650D03*
X148950Y109600D03*
X116100Y169700D03*
X120400Y169800D03*
X125300Y170200D03*
X163300Y178900D03*
X240100Y20900D03*
X221900Y5100D03*
X235600Y5300D03*
X247200Y5400D03*
X195200Y5700D03*
X191875Y-53409D03*
X201324D03*
X210773D03*
X220221D03*
X229670D03*
X239119D03*
X248568D03*
X258017D03*
X267466D03*
X252300Y22200D03*
X255900Y35000D03*
X246500Y47900D03*
X200500Y31500D03*
X216300Y46700D03*
X226600Y21400D03*
X198300Y73200D03*
X196400Y91600D03*
X193900Y51600D03*
X202800Y50200D03*
X218900Y65600D03*
X198900Y21200D03*
X230300Y45100D03*
X233800Y66000D03*
X262400Y169900D03*
X202300Y165100D03*
X196850Y177950D03*
X242800Y200600D03*
X243000Y185300D03*
X239400Y191500D03*
X345042Y-41479D03*
X339942D03*
X324642D03*
X334842D03*
X329742D03*
X319070Y-41541D03*
X276914Y-53409D03*
X286363D03*
X295812D03*
X305261D03*
X314710D03*
X324158D03*
X333607D03*
X343056D03*
X328000Y30500D03*
Y59000D03*
X339649Y41539D03*
X328655Y170950D03*
X326600Y182000D03*
X295800Y195900D03*
X396042Y-41479D03*
X390942D03*
X380742D03*
X385842D03*
X375642D03*
X370542D03*
X365442D03*
X360342D03*
X355242D03*
X401142D03*
X350142D03*
X423852Y4375D03*
X420252Y-36925D03*
X410052Y-36825D03*
X380500Y17100D03*
X352505Y-53409D03*
X361954D03*
X371403D03*
X380851D03*
X390300D03*
X399815Y-52741D03*
X415100Y3400D03*
X352600Y7600D03*
X380200Y6800D03*
X405500Y29200D03*
X370400Y88200D03*
X377800Y87800D03*
X383300Y50700D03*
X383500Y65800D03*
X388000Y41600D03*
X394500Y34000D03*
X380300Y21600D03*
X405800Y21100D03*
Y94200D03*
X405600Y87500D03*
X420322Y56072D03*
X423202Y56119D03*
X426128Y50188D03*
Y53348D03*
X426065Y56213D03*
X426113Y59046D03*
X425971Y62050D03*
X423500Y34200D03*
X416300Y37100D03*
X418705Y34695D03*
X405569Y72731D03*
X409026Y61211D03*
X401211Y46589D03*
X373300Y35400D03*
X384000Y41600D03*
X391600Y29400D03*
X361600Y69100D03*
X436752Y4175D03*
X498052Y-625D03*
X490200Y-6400D03*
X488652Y-18225D03*
X496352Y-19025D03*
X432452Y-36225D03*
X447252Y-47725D03*
X445252Y-37225D03*
X455701Y-53425D03*
X502945D03*
X493496D03*
X484047D03*
X474598D03*
X465149D03*
X446252D03*
X469300Y87600D03*
X459652Y31575D03*
X458100Y47300D03*
Y53700D03*
X448200Y93000D03*
X448369Y86631D03*
X432091Y56151D03*
X429056Y56135D03*
X457400Y41800D03*
X468588Y55981D03*
X431382Y35283D03*
X437300Y91100D03*
X454085Y63272D03*
X460535Y76560D03*
X456662Y76376D03*
X452496Y70099D03*
X454500Y29300D03*
X439418Y26110D03*
X452888Y108444D03*
X457097Y108548D03*
X466361Y230936D03*
X467506Y226106D03*
X502000Y229400D03*
X466010Y216328D03*
X492961Y227336D03*
X480761Y227936D03*
X505961Y236936D03*
X488161Y236336D03*
X479761D03*
X499761D03*
X532137Y7890D03*
X532691Y-17725D03*
X531600Y-31800D03*
X523300Y-32100D03*
X531291Y-53425D03*
X521842D03*
X512393D03*
X534737Y40290D03*
X534337Y52790D03*
X534637Y74290D03*
Y92590D03*
X532778Y21738D03*
X512000Y158400D03*
X511900Y174400D03*
Y142700D03*
X521900Y179500D03*
X548200Y169900D03*
X548300Y178100D03*
X578337Y166890D03*
X577748Y181113D03*
X529000Y158500D03*
X521600Y158400D03*
X524200Y181600D03*
X519700Y181900D03*
X521900Y184000D03*
X545300Y236800D03*
X529500Y236400D03*
X519761Y236336D03*
X537200Y236400D03*
X559761Y236336D03*
X579761D03*
X577748Y211113D03*
X578337Y226890D03*
X577748Y191113D03*
Y201113D03*
X524000Y200000D03*
X593337Y166890D03*
Y176890D03*
X608337Y166890D03*
Y176890D03*
X599761Y236336D03*
X593337Y206890D03*
Y216890D03*
Y226890D03*
Y186890D03*
Y196890D03*
X608337Y206890D03*
Y216890D03*
Y226890D03*
Y186890D03*
Y196890D03*
G54D20*
X539370Y190256D03*
Y206792D03*
X561024Y190256D03*
Y206792D03*
G54D16*
X168268Y143189D03*
Y223189D03*
X456258Y143189D03*
Y223189D03*
G54D10*
X21800Y-41500D03*
X14794Y226306D03*
X542107Y17432D03*
X585785Y228866D03*
X610300Y-43600D03*
X612500Y540800D03*
G54D19*
X383600Y55532D03*
X528590Y-12237D03*
Y2763D03*
G54D18*
X134213Y155984D03*
X173583D03*
X185393Y148109D03*
X134213Y130394D03*
X146023Y138269D03*
X177518D03*
X189333Y130394D03*
X134213Y235984D03*
X173583D03*
X185393Y228109D03*
X134213Y210394D03*
X146023Y218269D03*
X177518D03*
X189333Y210394D03*
X197203Y155984D03*
X205078D03*
X216888Y148109D03*
X220828Y155984D03*
X232638Y148109D03*
X236573Y155984D03*
X248388Y148109D03*
X260198Y155984D03*
X197203Y130394D03*
X209018Y138269D03*
X212953Y130394D03*
X224763Y138269D03*
X228703Y130394D03*
X240513Y138269D03*
X252323Y130394D03*
X264133Y138269D03*
X268073Y130394D03*
X197203Y235984D03*
X205078D03*
X216888Y228109D03*
X220828Y235984D03*
X232638Y228109D03*
X236573Y235984D03*
X248388Y228109D03*
X260198Y235984D03*
X197203Y210394D03*
X209018Y218269D03*
X212953Y210394D03*
X224763Y218269D03*
X228703Y210394D03*
X240513Y218269D03*
X252323Y210394D03*
X264133Y218269D03*
X268073Y210394D03*
X272008Y148109D03*
X275943Y155984D03*
X287758Y148109D03*
X291693Y155984D03*
X303503Y148109D03*
X307443Y155984D03*
X319253Y148109D03*
X327128D03*
X338938Y155984D03*
X342873Y148109D03*
X279883Y138269D03*
X283818Y130394D03*
X295628Y138269D03*
X299568Y130394D03*
X311378Y138269D03*
X319253D03*
X331063Y130394D03*
X334998Y138269D03*
X346813Y130394D03*
X272008Y228109D03*
X275943Y235984D03*
X287758Y228109D03*
X291693Y235984D03*
X303503Y228109D03*
X307443Y235984D03*
X319253Y228109D03*
X327128D03*
X338938Y235984D03*
X342873Y228109D03*
X279883Y218269D03*
X283818Y210394D03*
X295628Y218269D03*
X299568Y210394D03*
X311378Y218269D03*
X319253D03*
X331063Y210394D03*
X334998Y218269D03*
X346813Y210394D03*
X354683Y155984D03*
X358623Y148109D03*
X370433Y155984D03*
X374368Y148109D03*
X386183Y155984D03*
X390118Y148109D03*
X401928Y155984D03*
X405868Y148109D03*
X417678Y155984D03*
X421613Y148109D03*
X350748Y138269D03*
X362558Y130394D03*
X366498Y138269D03*
X378308Y130394D03*
X382243Y138269D03*
X394053Y130394D03*
X397993Y138269D03*
X409803Y130394D03*
X413738Y138269D03*
X425553Y130394D03*
X429488Y138269D03*
X354683Y235984D03*
X358623Y228109D03*
X370433Y235984D03*
X374368Y228109D03*
X386183Y235984D03*
X390118Y228109D03*
X401928Y235984D03*
X405868Y228109D03*
X417678Y235984D03*
X421613Y228109D03*
X350748Y218269D03*
X362558Y210394D03*
X366498Y218269D03*
X378308Y210394D03*
X382243Y218269D03*
X394053Y210394D03*
X397993Y218269D03*
X409803Y210394D03*
X413738Y218269D03*
X425553Y210394D03*
X429488Y218269D03*
X433423Y155984D03*
X437363Y148109D03*
X449173Y155984D03*
X441298Y130394D03*
X433423Y235984D03*
X437363Y228109D03*
X449173Y235984D03*
X441298Y210394D03*
%LPC*%
G75*
G54D21*
G01X-84798Y-164972D02*
Y-244972D01*
G01D02*
X1172402D01*
G01X-88798Y-148972D02*
G02I-12000J0D01*
G01X-93948D02*
G02I-6850J0D01*
G01X-100798Y-164972D02*
Y-132972D01*
G01X-84798Y-148972D02*
X-116798D01*
G01X-84798Y-164972D02*
X1172402D01*
G01X-84798Y-200472D02*
X1172402D01*
G01X384902Y-164972D02*
Y-244972D01*
G01X522402Y-164972D02*
Y-244972D01*
G01X637402Y-164972D02*
Y-244972D01*
G01X804902Y-164972D02*
Y-244972D01*
G01X974902Y-164972D02*
Y-244972D01*
G01X1172402Y-164972D02*
Y-244972D01*
G01X1200402Y-148972D02*
G02I-12000J0D01*
G01X1195252D02*
G02I-6850J0D01*
G01X1188402Y-164972D02*
Y-132972D01*
G01X1204402Y-148972D02*
X1172402D01*
G54D22*
G01X-65001Y-234972D02*
Y-217472D01*
X-60635D01*
X-58888Y-218347D01*
X-57578Y-219514D01*
X-56486Y-221263D01*
X-55613Y-223306D01*
X-55395Y-226222D01*
X-55613Y-229139D01*
X-56486Y-231181D01*
X-57578Y-232931D01*
X-58888Y-234097D01*
X-60635Y-234972D01*
X-65001D01*
G01X-48157Y-217472D02*
X-42698Y-234972D01*
X-37239Y-217472D01*
G01X-25198D02*
Y-234972D01*
G01X-30220Y-217472D02*
X-20176D01*
G01X5435Y-234972D02*
Y-217472D01*
X10894D01*
X12640Y-218347D01*
X13732Y-219514D01*
X14169Y-221847D01*
X13732Y-224181D01*
X12422Y-225639D01*
X10894Y-226514D01*
X5435D01*
G01X10894D02*
X14169Y-234972D01*
G01X27302Y-223306D02*
Y-234972D01*
G01Y-218639D02*
X26865Y-218347D01*
Y-217764D01*
X27302Y-217472D01*
X27739Y-217764D01*
Y-218347D01*
X27302Y-218639D01*
G01X41527Y-232931D02*
X42619Y-234097D01*
X44147Y-234972D01*
X45457D01*
X46767Y-234389D01*
X47640Y-233514D01*
X48077Y-232348D01*
X47859Y-230597D01*
X46985Y-229722D01*
X43055Y-227972D01*
X42182Y-225930D01*
X42619Y-224472D01*
X43492Y-223597D01*
X44802Y-223306D01*
X46112Y-223597D01*
X47422Y-224472D01*
G01X59027Y-227097D02*
X66014D01*
X65359Y-225055D01*
X64267Y-223889D01*
X62739Y-223306D01*
X61210Y-223597D01*
X59900Y-224472D01*
X59027Y-226514D01*
X58590Y-228264D01*
Y-230014D01*
X59027Y-231764D01*
X60119Y-233514D01*
X61429Y-234680D01*
X62957Y-234972D01*
X64485Y-234389D01*
X66014Y-232639D01*
G01X76745Y-234972D02*
Y-223306D01*
G01Y-225639D02*
X77837Y-224472D01*
X78929Y-223597D01*
X80457Y-223306D01*
X81548Y-223597D01*
X82859Y-224472D01*
G01X119605Y-218931D02*
X118295Y-218055D01*
X116767Y-217472D01*
X115020D01*
X113055Y-218347D01*
X111527Y-219805D01*
X110435Y-221556D01*
X109562Y-224472D01*
X109343Y-227097D01*
X109780Y-229722D01*
X110435Y-231472D01*
X111745Y-233222D01*
X113274Y-234389D01*
X114802Y-234972D01*
X116330D01*
X117859Y-234389D01*
X119169Y-233514D01*
X120261Y-232348D01*
G01X136232Y-234972D02*
Y-223306D01*
G01Y-225347D02*
X135359Y-224181D01*
X134048Y-223597D01*
X132520Y-223306D01*
X130992Y-223889D01*
X129682Y-225055D01*
X128808Y-226805D01*
X128372Y-229139D01*
X128808Y-231472D01*
X129682Y-233222D01*
X130992Y-234389D01*
X132520Y-234972D01*
X134048Y-234680D01*
X135359Y-233806D01*
X136232Y-232639D01*
G01X146745Y-234972D02*
Y-223306D01*
G01Y-225639D02*
X147837Y-224472D01*
X148929Y-223597D01*
X150457Y-223306D01*
X151548Y-223597D01*
X152859Y-224472D01*
G01X171232Y-217472D02*
Y-234972D01*
G01Y-232348D02*
X170359Y-233806D01*
X169048Y-234680D01*
X167520Y-234972D01*
X165774Y-234389D01*
X164464Y-232931D01*
X163590Y-231181D01*
X163372Y-229139D01*
X163590Y-227097D01*
X164464Y-225347D01*
X165774Y-223889D01*
X167520Y-223306D01*
X169048Y-223597D01*
X170140Y-224181D01*
X171232Y-225347D01*
G01X178252Y-240805D02*
X191352D01*
G01X197717Y-232639D02*
X199464Y-234097D01*
X201429Y-234972D01*
X203175D01*
X204922Y-234097D01*
X206232Y-232639D01*
X206887Y-230597D01*
X206450Y-228556D01*
X205359Y-226805D01*
X203394Y-225639D01*
X200774Y-225055D01*
X199245Y-223889D01*
X198590Y-221847D01*
X199027Y-219805D01*
X200119Y-218347D01*
X201647Y-217472D01*
X203175D01*
X204704Y-218055D01*
X206014Y-219514D01*
G01X215217Y-232639D02*
X216964Y-234097D01*
X218929Y-234972D01*
X220675D01*
X222422Y-234097D01*
X223732Y-232639D01*
X224387Y-230597D01*
X223950Y-228556D01*
X222859Y-226805D01*
X220894Y-225639D01*
X218274Y-225055D01*
X216745Y-223889D01*
X216090Y-221847D01*
X216527Y-219805D01*
X217619Y-218347D01*
X219147Y-217472D01*
X220675D01*
X222204Y-218055D01*
X223514Y-219514D01*
G01X250654Y-220389D02*
X251964Y-218639D01*
X253492Y-217764D01*
X255239Y-217472D01*
X257422Y-218055D01*
X258950Y-219514D01*
X259387Y-221263D01*
X259169Y-223014D01*
X258295Y-224472D01*
X253929Y-227389D01*
X251964Y-229430D01*
X250654Y-232348D01*
X250217Y-234972D01*
X259387D01*
G01X286527Y-232931D02*
X287619Y-234097D01*
X289147Y-234972D01*
X290457D01*
X291767Y-234389D01*
X292640Y-233514D01*
X293077Y-232348D01*
X292859Y-230597D01*
X291985Y-229722D01*
X288055Y-227972D01*
X287182Y-225930D01*
X287619Y-224472D01*
X288492Y-223597D01*
X289802Y-223306D01*
X291112Y-223597D01*
X292422Y-224472D01*
G01X307302Y-234972D02*
Y-217472D01*
G01X324802Y-234972D02*
X323492Y-234680D01*
X322182Y-233514D01*
X321308Y-231472D01*
X320872Y-229139D01*
X321308Y-226805D01*
X322182Y-224764D01*
X323492Y-223597D01*
X324802Y-223306D01*
X326112Y-223597D01*
X327422Y-224764D01*
X328295Y-226805D01*
X328514Y-229139D01*
X328295Y-231472D01*
X327422Y-233514D01*
X326112Y-234680D01*
X324802Y-234972D01*
G01X342302Y-217472D02*
Y-234972D01*
G01X339245Y-223306D02*
X345359D01*
G01X356527Y-232931D02*
X357619Y-234097D01*
X359147Y-234972D01*
X360457D01*
X361767Y-234389D01*
X362640Y-233514D01*
X363077Y-232348D01*
X362859Y-230597D01*
X361985Y-229722D01*
X358055Y-227972D01*
X357182Y-225930D01*
X357619Y-224472D01*
X358492Y-223597D01*
X359802Y-223306D01*
X361112Y-223597D01*
X362422Y-224472D01*
G01X109125Y-189972D02*
Y-172472D01*
X114802Y-187055D01*
X120479Y-172472D01*
Y-189972D01*
G01X132302D02*
X130992Y-189680D01*
X129682Y-188514D01*
X128808Y-186472D01*
X128372Y-184139D01*
X128808Y-181805D01*
X129682Y-179764D01*
X130992Y-178597D01*
X132302Y-178306D01*
X133612Y-178597D01*
X134922Y-179764D01*
X135795Y-181805D01*
X136014Y-184139D01*
X135795Y-186472D01*
X134922Y-188514D01*
X133612Y-189680D01*
X132302Y-189972D01*
G01X153732Y-172472D02*
Y-189972D01*
G01Y-187348D02*
X152859Y-188806D01*
X151548Y-189680D01*
X150020Y-189972D01*
X148274Y-189389D01*
X146964Y-187931D01*
X146090Y-186181D01*
X145872Y-184139D01*
X146090Y-182097D01*
X146964Y-180347D01*
X148274Y-178889D01*
X150020Y-178306D01*
X151548Y-178597D01*
X152640Y-179181D01*
X153732Y-180347D01*
G01X164027Y-182097D02*
X171014D01*
X170359Y-180055D01*
X169267Y-178889D01*
X167739Y-178306D01*
X166210Y-178597D01*
X164900Y-179472D01*
X164027Y-181514D01*
X163590Y-183264D01*
Y-185014D01*
X164027Y-186764D01*
X165119Y-188514D01*
X166429Y-189680D01*
X167957Y-189972D01*
X169485Y-189389D01*
X171014Y-187639D01*
G01X184802Y-189972D02*
Y-172472D01*
G01X418602Y-234972D02*
Y-217472D01*
X415982Y-220972D01*
G01Y-234972D02*
X421222D01*
G01X431299Y-232348D02*
X432608Y-233806D01*
X434137Y-234680D01*
X436102Y-234972D01*
X438067Y-234389D01*
X439595Y-233222D01*
X440687Y-231181D01*
X440905Y-228847D01*
X440469Y-226514D01*
X439377Y-225055D01*
X437848Y-223889D01*
X436320Y-223597D01*
X434792Y-223889D01*
X432827Y-225055D01*
X433482Y-217472D01*
X439377D01*
G01X449890Y-232931D02*
X451419Y-234389D01*
X453165Y-234972D01*
X454912Y-234389D01*
X456440Y-232639D01*
X457532Y-230014D01*
X457969Y-227389D01*
Y-224181D01*
X457532Y-221556D01*
X456440Y-219222D01*
X455130Y-218055D01*
X453602Y-217472D01*
X451855Y-218055D01*
X450545Y-219222D01*
X449672Y-220972D01*
X449235Y-223306D01*
X449672Y-225347D01*
X450764Y-227389D01*
X452074Y-228556D01*
X453602Y-228847D01*
X455348Y-228264D01*
X456659Y-226805D01*
X457969Y-224181D01*
G01X466954Y-227681D02*
X468482Y-225639D01*
X469792Y-224472D01*
X471539Y-223889D01*
X473067Y-224472D01*
X474159Y-225639D01*
X475032Y-227389D01*
X475250Y-229430D01*
X475032Y-231181D01*
X474159Y-232931D01*
X472848Y-234389D01*
X471320Y-234972D01*
X469574Y-234389D01*
X468045Y-232639D01*
X467172Y-230014D01*
X466954Y-227097D01*
X467390Y-223306D01*
X468045Y-221263D01*
X469137Y-219222D01*
X470665Y-217764D01*
X472194Y-217472D01*
X473722Y-218055D01*
X474814Y-219514D01*
G01X488602Y-234972D02*
X490130Y-234680D01*
X491877Y-233806D01*
X492969Y-232348D01*
X493405Y-230305D01*
X492969Y-228264D01*
X491659Y-226514D01*
X489694Y-225639D01*
X487510D01*
X486200Y-225055D01*
X485108Y-223597D01*
X484672Y-221556D01*
X485327Y-219514D01*
X486855Y-218055D01*
X488602Y-217472D01*
X490348Y-218055D01*
X491877Y-219514D01*
X492532Y-221556D01*
X492095Y-223597D01*
X491004Y-225055D01*
X489694Y-225639D01*
X487510D01*
X485545Y-226514D01*
X484235Y-228264D01*
X483799Y-230305D01*
X484235Y-232348D01*
X485327Y-233806D01*
X487074Y-234680D01*
X488602Y-234972D01*
G01X405485Y-189972D02*
Y-172472D01*
X410725D01*
X412472Y-173347D01*
X413782Y-175389D01*
X414219Y-177722D01*
X413782Y-180055D01*
X412690Y-181805D01*
X410725Y-182681D01*
X405485D01*
G01X432155Y-173931D02*
X430845Y-173055D01*
X429317Y-172472D01*
X427570D01*
X425605Y-173347D01*
X424077Y-174805D01*
X422985Y-176556D01*
X422112Y-179472D01*
X421893Y-182097D01*
X422330Y-184722D01*
X422985Y-186472D01*
X424295Y-188222D01*
X425824Y-189389D01*
X427352Y-189972D01*
X428880D01*
X430409Y-189389D01*
X431719Y-188514D01*
X432811Y-187348D01*
G01X446598Y-180639D02*
X447472Y-179764D01*
X448127Y-178306D01*
X448564Y-176263D01*
X448127Y-174514D01*
X447254Y-173347D01*
X445725Y-172472D01*
X439830D01*
Y-189972D01*
X447035D01*
X448564Y-188806D01*
X449437Y-187055D01*
X449874Y-185014D01*
X449437Y-182972D01*
X448127Y-181222D01*
X446598Y-180639D01*
X439830D01*
G01X455802Y-195805D02*
X468902D01*
G01X474830Y-189972D02*
Y-172472D01*
X484874Y-189972D01*
Y-172472D01*
G01X497352Y-189972D02*
X495605Y-189680D01*
X494077Y-188514D01*
X492767Y-186764D01*
X491893Y-184722D01*
X491457Y-182389D01*
Y-180055D01*
X491893Y-177722D01*
X492767Y-175680D01*
X494077Y-173931D01*
X495605Y-172764D01*
X497352Y-172472D01*
X499098Y-172764D01*
X500627Y-173931D01*
X501937Y-175680D01*
X502811Y-177722D01*
X503247Y-180055D01*
Y-182389D01*
X502811Y-184722D01*
X501937Y-186764D01*
X500627Y-188514D01*
X499098Y-189680D01*
X497352Y-189972D01*
G01X571152Y-234972D02*
Y-217472D01*
X568532Y-220972D01*
G01Y-234972D02*
X573772D01*
G01X583193D02*
X588652Y-217472D01*
X594111Y-234972D01*
G01X592145Y-228847D02*
X585158D01*
G01X548193Y-172472D02*
X553652Y-189972D01*
X559111Y-172472D01*
G01X575519Y-189972D02*
X566785D01*
Y-172472D01*
X575519D01*
G01X572025Y-180930D02*
X566785D01*
G01X584285Y-189972D02*
Y-172472D01*
X589744D01*
X591490Y-173347D01*
X592582Y-174514D01*
X593019Y-176847D01*
X592582Y-179181D01*
X591272Y-180639D01*
X589744Y-181514D01*
X584285D01*
G01X589744D02*
X593019Y-189972D01*
G01X606152Y-190555D02*
X605715Y-190264D01*
Y-189680D01*
X606152Y-189389D01*
X606589Y-189680D01*
Y-190264D01*
X606152Y-190555D01*
G01X760469Y-217472D02*
Y-234972D01*
X751735D01*
G01X743405Y-232348D02*
X742096Y-233806D01*
X740567Y-234680D01*
X738602Y-234972D01*
X736637Y-234389D01*
X735109Y-233222D01*
X734017Y-231181D01*
X733799Y-228847D01*
X734235Y-226514D01*
X735327Y-225055D01*
X736856Y-223889D01*
X738384Y-223597D01*
X739912Y-223889D01*
X741877Y-225055D01*
X741222Y-217472D01*
X735327D01*
G01X719792Y-226222D02*
X715425D01*
Y-231472D01*
X716735Y-233222D01*
X718264Y-234389D01*
X720447Y-234972D01*
X722630Y-234389D01*
X724159Y-233222D01*
X725469Y-231472D01*
X726342Y-229430D01*
X726779Y-227097D01*
Y-225055D01*
X726342Y-223306D01*
X725469Y-221263D01*
X724159Y-219514D01*
X722849Y-218347D01*
X721102Y-217472D01*
X719574D01*
X717827Y-218055D01*
X716517Y-219222D01*
G01X708624Y-234972D02*
Y-217472D01*
X698580Y-234972D01*
Y-217472D01*
G01X690905Y-234972D02*
Y-217472D01*
X686539D01*
X684792Y-218347D01*
X683482Y-219514D01*
X682390Y-221263D01*
X681517Y-223306D01*
X681299Y-226222D01*
X681517Y-229139D01*
X682390Y-231181D01*
X683482Y-232931D01*
X684792Y-234097D01*
X686539Y-234972D01*
X690905D01*
G01X681735Y-172472D02*
Y-189972D01*
X690469D01*
G01X707532D02*
Y-178306D01*
G01Y-180347D02*
X706659Y-179181D01*
X705348Y-178597D01*
X703820Y-178306D01*
X702292Y-178889D01*
X700982Y-180055D01*
X700108Y-181805D01*
X699672Y-184139D01*
X700108Y-186472D01*
X700982Y-188222D01*
X702292Y-189389D01*
X703820Y-189972D01*
X705348Y-189680D01*
X706659Y-188806D01*
X707532Y-187639D01*
G01X716517Y-195222D02*
X717827Y-195805D01*
X719574Y-195222D01*
X720665Y-194056D01*
X721539Y-192597D01*
X722848Y-187931D01*
X725687Y-178306D01*
G01X718700D02*
X722848Y-187931D01*
G01X735327Y-182097D02*
X742314D01*
X741659Y-180055D01*
X740567Y-178889D01*
X739039Y-178306D01*
X737510Y-178597D01*
X736200Y-179472D01*
X735327Y-181514D01*
X734890Y-183264D01*
Y-185014D01*
X735327Y-186764D01*
X736419Y-188514D01*
X737729Y-189680D01*
X739257Y-189972D01*
X740785Y-189389D01*
X742314Y-187639D01*
G01X753045Y-189972D02*
Y-178306D01*
G01Y-180639D02*
X754137Y-179472D01*
X755229Y-178597D01*
X756757Y-178306D01*
X757848Y-178597D01*
X759159Y-179472D01*
G01X824705Y-218931D02*
X823395Y-218055D01*
X821867Y-217472D01*
X820120D01*
X818155Y-218347D01*
X816627Y-219805D01*
X815535Y-221556D01*
X814662Y-224472D01*
X814443Y-227097D01*
X814880Y-229722D01*
X815535Y-231472D01*
X816845Y-233222D01*
X818374Y-234389D01*
X819902Y-234972D01*
X821430D01*
X822959Y-234389D01*
X824269Y-233514D01*
X825361Y-232348D01*
G01X837402Y-234972D02*
X835655Y-234680D01*
X834127Y-233514D01*
X832817Y-231764D01*
X831943Y-229722D01*
X831507Y-227389D01*
Y-225055D01*
X831943Y-222722D01*
X832817Y-220680D01*
X834127Y-218931D01*
X835655Y-217764D01*
X837402Y-217472D01*
X839148Y-217764D01*
X840677Y-218931D01*
X841987Y-220680D01*
X842861Y-222722D01*
X843297Y-225055D01*
Y-227389D01*
X842861Y-229722D01*
X841987Y-231764D01*
X840677Y-233514D01*
X839148Y-234680D01*
X837402Y-234972D01*
G01X849880D02*
Y-217472D01*
X859924Y-234972D01*
Y-217472D01*
G01X867380Y-234972D02*
Y-217472D01*
X877424Y-234972D01*
Y-217472D01*
G01X887282D02*
X892522D01*
G01X889902D02*
Y-234972D01*
G01X887282D02*
X892522D01*
G01X911769D02*
X903035D01*
Y-217472D01*
X911769D01*
G01X908275Y-225930D02*
X903035D01*
G01X937817Y-234972D02*
X946987Y-217472D01*
G01X937817D02*
X946987Y-234972D01*
G01X955317D02*
Y-217472D01*
G01X964487D02*
Y-234972D01*
G01Y-226222D02*
X955317D01*
G01X823849Y-189972D02*
Y-172472D01*
X828215D01*
X829962Y-173347D01*
X831272Y-174514D01*
X832364Y-176263D01*
X833237Y-178306D01*
X833455Y-181222D01*
X833237Y-184139D01*
X832364Y-186181D01*
X831272Y-187931D01*
X829962Y-189097D01*
X828215Y-189972D01*
X823849D01*
G01X842877Y-182097D02*
X849864D01*
X849209Y-180055D01*
X848117Y-178889D01*
X846589Y-178306D01*
X845060Y-178597D01*
X843750Y-179472D01*
X842877Y-181514D01*
X842440Y-183264D01*
Y-185014D01*
X842877Y-186764D01*
X843969Y-188514D01*
X845279Y-189680D01*
X846807Y-189972D01*
X848335Y-189389D01*
X849864Y-187639D01*
G01X860377Y-187931D02*
X861469Y-189097D01*
X862997Y-189972D01*
X864307D01*
X865617Y-189389D01*
X866490Y-188514D01*
X866927Y-187348D01*
X866709Y-185597D01*
X865835Y-184722D01*
X861905Y-182972D01*
X861032Y-180930D01*
X861469Y-179472D01*
X862342Y-178597D01*
X863652Y-178306D01*
X864962Y-178597D01*
X866272Y-179472D01*
G01X881152Y-178306D02*
Y-189972D01*
G01Y-173639D02*
X880715Y-173347D01*
Y-172764D01*
X881152Y-172472D01*
X881589Y-172764D01*
Y-173347D01*
X881152Y-173639D01*
G01X895595Y-194347D02*
X897124Y-195514D01*
X898870Y-195805D01*
X900398Y-195514D01*
X901709Y-194056D01*
X902582Y-192014D01*
Y-178306D01*
G01Y-180639D02*
X901709Y-179472D01*
X900398Y-178597D01*
X898870Y-178306D01*
X897124Y-178889D01*
X896032Y-180055D01*
X895158Y-182097D01*
X894722Y-184139D01*
X894940Y-185889D01*
X895814Y-187931D01*
X897124Y-189389D01*
X898870Y-189972D01*
X900180Y-189680D01*
X901709Y-188514D01*
X902582Y-187348D01*
G01X912440Y-189972D02*
Y-178306D01*
G01Y-181222D02*
X913314Y-179764D01*
X914624Y-178597D01*
X916370Y-178306D01*
X917898Y-178597D01*
X919209Y-179764D01*
X919864Y-181805D01*
Y-189972D01*
G01X930377Y-182097D02*
X937364D01*
X936709Y-180055D01*
X935617Y-178889D01*
X934089Y-178306D01*
X932560Y-178597D01*
X931250Y-179472D01*
X930377Y-181514D01*
X929940Y-183264D01*
Y-185014D01*
X930377Y-186764D01*
X931469Y-188514D01*
X932779Y-189680D01*
X934307Y-189972D01*
X935835Y-189389D01*
X937364Y-187639D01*
G01X948095Y-189972D02*
Y-178306D01*
G01Y-180639D02*
X949187Y-179472D01*
X950279Y-178597D01*
X951807Y-178306D01*
X952898Y-178597D01*
X954209Y-179472D01*
G01X994852Y-217472D02*
X993105Y-218055D01*
X991795Y-219514D01*
X990922Y-221263D01*
X990267Y-223597D01*
X990049Y-226222D01*
X990267Y-228847D01*
X990922Y-231181D01*
X991795Y-232931D01*
X993105Y-234389D01*
X994852Y-234972D01*
X996598Y-234389D01*
X997909Y-232931D01*
X998782Y-231181D01*
X999437Y-228847D01*
X999655Y-226222D01*
X999437Y-223597D01*
X998782Y-221263D01*
X997909Y-219514D01*
X996598Y-218055D01*
X994852Y-217472D01*
G01X1012352Y-234972D02*
X1013880Y-234680D01*
X1015627Y-233806D01*
X1016719Y-232348D01*
X1017155Y-230305D01*
X1016719Y-228264D01*
X1015409Y-226514D01*
X1013444Y-225639D01*
X1011260D01*
X1009950Y-225055D01*
X1008858Y-223597D01*
X1008422Y-221556D01*
X1009077Y-219514D01*
X1010605Y-218055D01*
X1012352Y-217472D01*
X1014098Y-218055D01*
X1015627Y-219514D01*
X1016282Y-221556D01*
X1015845Y-223597D01*
X1014754Y-225055D01*
X1013444Y-225639D01*
X1011260D01*
X1009295Y-226514D01*
X1007985Y-228264D01*
X1007549Y-230305D01*
X1007985Y-232348D01*
X1009077Y-233806D01*
X1010824Y-234680D01*
X1012352Y-234972D01*
G01X1025922Y-235555D02*
X1033782Y-217472D01*
G01X1043204Y-220389D02*
X1044514Y-218639D01*
X1046042Y-217764D01*
X1047789Y-217472D01*
X1049972Y-218055D01*
X1051500Y-219514D01*
X1051937Y-221263D01*
X1051719Y-223014D01*
X1050845Y-224472D01*
X1046479Y-227389D01*
X1044514Y-229430D01*
X1043204Y-232348D01*
X1042767Y-234972D01*
X1051937D01*
G01X1060049Y-232348D02*
X1061358Y-233806D01*
X1062887Y-234680D01*
X1064852Y-234972D01*
X1066817Y-234389D01*
X1068345Y-233222D01*
X1069437Y-231181D01*
X1069655Y-228847D01*
X1069219Y-226514D01*
X1068127Y-225055D01*
X1066598Y-223889D01*
X1065070Y-223597D01*
X1063542Y-223889D01*
X1061577Y-225055D01*
X1062232Y-217472D01*
X1068127D01*
G01X1078422Y-235555D02*
X1086282Y-217472D01*
G01X1095704Y-220389D02*
X1097014Y-218639D01*
X1098542Y-217764D01*
X1100289Y-217472D01*
X1102472Y-218055D01*
X1104000Y-219514D01*
X1104437Y-221263D01*
X1104219Y-223014D01*
X1103345Y-224472D01*
X1098979Y-227389D01*
X1097014Y-229430D01*
X1095704Y-232348D01*
X1095267Y-234972D01*
X1104437D01*
G01X1117352Y-217472D02*
X1115605Y-218055D01*
X1114295Y-219514D01*
X1113422Y-221263D01*
X1112767Y-223597D01*
X1112549Y-226222D01*
X1112767Y-228847D01*
X1113422Y-231181D01*
X1114295Y-232931D01*
X1115605Y-234389D01*
X1117352Y-234972D01*
X1119098Y-234389D01*
X1120409Y-232931D01*
X1121282Y-231181D01*
X1121937Y-228847D01*
X1122155Y-226222D01*
X1121937Y-223597D01*
X1121282Y-221263D01*
X1120409Y-219514D01*
X1119098Y-218055D01*
X1117352Y-217472D01*
G01X1134852Y-234972D02*
Y-217472D01*
X1132232Y-220972D01*
G01Y-234972D02*
X1137472D01*
G01X1148204Y-227681D02*
X1149732Y-225639D01*
X1151042Y-224472D01*
X1152789Y-223889D01*
X1154317Y-224472D01*
X1155409Y-225639D01*
X1156282Y-227389D01*
X1156500Y-229430D01*
X1156282Y-231181D01*
X1155409Y-232931D01*
X1154098Y-234389D01*
X1152570Y-234972D01*
X1150824Y-234389D01*
X1149295Y-232639D01*
X1148422Y-230014D01*
X1148204Y-227097D01*
X1148640Y-223306D01*
X1149295Y-221263D01*
X1150387Y-219222D01*
X1151915Y-217764D01*
X1153444Y-217472D01*
X1154972Y-218055D01*
X1156064Y-219514D01*
G01X1042549Y-189972D02*
Y-172472D01*
X1046915D01*
X1048662Y-173347D01*
X1049972Y-174514D01*
X1051064Y-176263D01*
X1051937Y-178306D01*
X1052155Y-181222D01*
X1051937Y-184139D01*
X1051064Y-186181D01*
X1049972Y-187931D01*
X1048662Y-189097D01*
X1046915Y-189972D01*
X1042549D01*
G01X1068782D02*
Y-178306D01*
G01Y-180347D02*
X1067909Y-179181D01*
X1066598Y-178597D01*
X1065070Y-178306D01*
X1063542Y-178889D01*
X1062232Y-180055D01*
X1061358Y-181805D01*
X1060922Y-184139D01*
X1061358Y-186472D01*
X1062232Y-188222D01*
X1063542Y-189389D01*
X1065070Y-189972D01*
X1066598Y-189680D01*
X1067909Y-188806D01*
X1068782Y-187639D01*
G01X1082352Y-172472D02*
Y-189972D01*
G01X1079295Y-178306D02*
X1085409D01*
G01X1096577Y-182097D02*
X1103564D01*
X1102909Y-180055D01*
X1101817Y-178889D01*
X1100289Y-178306D01*
X1098760Y-178597D01*
X1097450Y-179472D01*
X1096577Y-181514D01*
X1096140Y-183264D01*
Y-185014D01*
X1096577Y-186764D01*
X1097669Y-188514D01*
X1098979Y-189680D01*
X1100507Y-189972D01*
X1102035Y-189389D01*
X1103564Y-187639D01*
M02*
